#ISCELL
  mstr_symbols design_note *
  *
#ISCELL
  mstr_symbols intel_corp_bpage *
  *
#CELL
  dev_discrete cap_a *
  page76_i1
#CELL
  dev_discrete cap_a *
  page76_i10
#CELL
  mstr_discrete cap *
  page76_i103
#CELL
  mstr_discrete cap *
  page76_i107
#CELL
  dev_discrete cap_a *
  page76_i108
#ISCELL
  mstr_symbols gnd *
  page76_i109
#CELL
  dev_discrete cap_a *
  page76_i112
#ISCELL
  mstr_symbols gnd *
  page76_i113
#CELL
  dev_discrete cap_a *
  page76_i114
#CELL
  mstr_discrete cap *
  page76_i118
#CELL
  dev_discrete cap_a *
  page76_i119
#CELL
  dev_discrete cap_a *
  page76_i122
#CELL
  dev_discrete cap_a *
  page76_i124
#CELL
  mstr_discrete cap *
  page76_i125
#CELL
  mstr_discrete cap *
  page76_i127
#CELL
  mstr_discrete cap *
  page76_i129
#ISCELL
  mstr_symbols gnd *
  page76_i130
#CELL
  mstr_discrete cap *
  page76_i132
#ISCELL
  mstr_symbols gnd *
  page76_i134
#CELL
  mstr_discrete cap *
  page76_i137
#CELL
  mstr_discrete cap *
  page76_i139
#ISCELL
  mstr_symbols pvccin_cpu1 *
  page76_i143
#ISCELL
  mstr_symbols pvccin_cpu1 *
  page76_i144
#ISCELL
  mstr_symbols pvccin_cpu1 *
  page76_i145
#ISCELL
  mstr_symbols pvccin_cpu1 *
  page76_i146
#ISCELL
  mstr_symbols pvccin_cpu1 *
  page76_i147
#CELL
  dev_discrete cap_a *
  page76_i15
#ISCELL
  mstr_symbols pvccin_cpu1 *
  page76_i153
#ISCELL
  mstr_symbols pvccin_cpu1 *
  page76_i154
#ISCELL
  mstr_symbols pvccin_cpu1 *
  page76_i155
#ISCELL
  mstr_symbols pvccin_cpu1 *
  page76_i156
#ISCELL
  mstr_symbols pvccin_cpu1 *
  page76_i157
#ISCELL
  mstr_symbols pvccin_cpu1 *
  page76_i158
#CELL
  dev_discrete cap_a *
  page76_i159
#ISCELL
  mstr_symbols gnd *
  page76_i16
#CELL
  dev_discrete cap_a *
  page76_i160
#CELL
  dev_discrete cap_a *
  page76_i161
#ISCELL
  mstr_symbols vcc_core *
  page76_i162
#ISCELL
  mstr_symbols vcc_core *
  page76_i163
#CELL
  dev_discrete cap_a *
  page76_i164
#CELL
  dev_discrete cap_a *
  page76_i165
#CELL
  dev_discrete cap_a *
  page76_i166
#ISCELL
  mstr_symbols pvccio_cpu1 *
  page76_i167
#CELL
  dev_discrete cap_a *
  page76_i169
#CELL
  dev_discrete cap_a *
  page76_i170
#CELL
  dev_discrete cap_a *
  page76_i171
#CELL
  dev_discrete cap_a *
  page76_i172
#CELL
  dev_discrete cap_a *
  page76_i174
#CELL
  dev_discrete cap_a *
  page76_i175
#CELL
  dev_discrete cap_a *
  page76_i176
#CELL
  dev_discrete cap_a *
  page76_i179
#CELL
  dev_discrete cap_a *
  page76_i18
#CELL
  dev_discrete cap_a *
  page76_i196
#CELL
  dev_discrete cap_a *
  page76_i197
#CELL
  dev_discrete cap_a *
  page76_i198
#CELL
  dev_discrete cap_a *
  page76_i199
#ISCELL
  mstr_symbols gnd *
  page76_i2
#CELL
  dev_discrete cap_a *
  page76_i206
#CELL
  dev_discrete cap_a *
  page76_i207
#CELL
  dev_discrete cap_a *
  page76_i208
#ISCELL
  mstr_symbols vcc_core *
  page76_i209
#ISCELL
  mstr_symbols gnd *
  page76_i210
#CELL
  mstr_discrete cap *
  page76_i215
#CELL
  mstr_discrete cap *
  page76_i217
#ISCELL
  mstr_symbols gnd *
  page76_i224
#ISCELL
  mstr_symbols gnd *
  page76_i228
#ISCELL
  mstr_symbols pvccin_cpu1 *
  page76_i229
#ISCELL
  mstr_symbols gnd *
  page76_i231
#ISCELL
  mstr_symbols gnd *
  page76_i233
#ISCELL
  mstr_symbols gnd *
  page76_i24
#ISCELL
  mstr_symbols gnd *
  page76_i240
#ISCELL
  mstr_symbols gnd *
  page76_i241
#ISCELL
  mstr_symbols pvccin_cpu1 *
  page76_i244
#CELL
  mstr_discrete cap *
  page76_i245
#CELL
  mstr_discrete cap *
  page76_i246
#CELL
  mstr_discrete cap *
  page76_i247
#CELL
  mstr_discrete cap *
  page76_i248
#CELL
  mstr_discrete cap *
  page76_i249
#CELL
  mstr_discrete cap *
  page76_i250
#CELL
  mstr_discrete cap *
  page76_i251
#CELL
  mstr_discrete cap *
  page76_i252
#ISCELL
  mstr_symbols gnd *
  page76_i253
#CELL
  dev_discrete cap_a *
  page76_i254
#CELL
  dev_discrete cap_a *
  page76_i256
#ISCELL
  mstr_symbols vcc_core *
  page76_i257
#CELL
  mstr_discrete cap *
  page76_i258
#CELL
  mstr_discrete cap *
  page76_i259
#CELL
  mstr_discrete cap *
  page76_i260
#CELL
  mstr_discrete cap *
  page76_i261
#CELL
  mstr_discrete cap *
  page76_i262
#CELL
  mstr_discrete cap *
  page76_i263
#CELL
  mstr_discrete cap *
  page76_i264
#CELL
  mstr_discrete cap *
  page76_i265
#CELL
  mstr_discrete cap *
  page76_i266
#CELL
  mstr_discrete cap *
  page76_i267
#CELL
  mstr_discrete cap *
  page76_i268
#CELL
  mstr_discrete cap *
  page76_i269
#CELL
  mstr_discrete cap *
  page76_i270
#CELL
  mstr_discrete cap *
  page76_i271
#CELL
  mstr_discrete cap *
  page76_i272
#CELL
  mstr_discrete cap *
  page76_i273
#CELL
  mstr_discrete cap *
  page76_i274
#CELL
  mstr_discrete cap *
  page76_i29
#CELL
  dev_discrete cap_a *
  page76_i3
#ISCELL
  mstr_symbols gnd *
  page76_i30
#CELL
  mstr_discrete cap *
  page76_i33
#ISCELL
  mstr_symbols gnd *
  page76_i36
#CELL
  mstr_discrete cap *
  page76_i37
#CELL
  dev_discrete cap_a *
  page76_i4
#ISCELL
  mstr_symbols pvsa_cpu1 *
  page76_i41
#CELL
  mstr_discrete cap *
  page76_i42
#CELL
  mstr_discrete cap *
  page76_i43
#ISCELL
  mstr_symbols pvccio_cpu1 *
  page76_i47
#CELL
  dev_discrete cap_a *
  page76_i5
#CELL
  mstr_discrete cap *
  page76_i51
#CELL
  mstr_discrete cap *
  page76_i52
#ISCELL
  mstr_symbols gnd *
  page76_i53
#ISCELL
  mstr_symbols pvsa_cpu1 *
  page76_i57
#CELL
  dev_discrete cap_a *
  page76_i59
#ISCELL
  mstr_symbols gnd *
  page76_i60
#CELL
  dev_discrete cap_a *
  page76_i61
#CELL
  dev_discrete cap_a *
  page76_i63
#CELL
  dev_discrete cap_a *
  page76_i65
#CELL
  dev_discrete cap_a *
  page76_i66
#ISCELL
  mstr_symbols gnd *
  page76_i67
#CELL
  dev_discrete cap_a *
  page76_i69
#CELL
  dev_discrete cap_a *
  page76_i7
#CELL
  dev_discrete cap_a *
  page76_i70
#ISCELL
  mstr_symbols pvccin_cpu1 *
  page76_i71
#CELL
  dev_discrete cap_a *
  page76_i73
#ISCELL
  mstr_symbols gnd *
  page76_i74
#CELL
  dev_discrete cap_a *
  page76_i75
#CELL
  dev_discrete cap_a *
  page76_i76
#ISCELL
  mstr_symbols gnd *
  page76_i77
#CELL
  dev_discrete cap_a *
  page76_i79
#CELL
  dev_discrete cap_a *
  page76_i8
#CELL
  dev_discrete cap_a *
  page76_i80
#CELL
  dev_discrete cap_a *
  page76_i82
#CELL
  dev_discrete cap_a *
  page76_i83
#CELL
  dev_discrete cap_a *
  page76_i85
#CELL
  mstr_discrete cap *
  page76_i89
#CELL
  dev_discrete cap_a *
  page76_i90
#CELL
  mstr_discrete cap *
  page76_i92
